(kicad_pcb
	(version 20221018)
	(generator pcbnew)
	(general
    (thickness 1.562)
  )
	(paper "A4")
	(title_block
    (title "Thunderbolt PCIe Adaper")
    (date "2024-07-09")
    (rev "1.0.3")
    (comment 1 "www.antmicro.com")
    (comment 2 "Antmicro Ltd.")
		(comment 9 "footprints 59-66 of 271")
	)
	(layers
    (0 "F.Cu" signal)
    (1 "In1.Cu" signal)
    (2 "In2.Cu" signal)
    (3 "In3.Cu" signal)
    (4 "In4.Cu" signal)
    (31 "B.Cu" signal)
    (32 "B.Adhes" user "B.Adhesive")
    (33 "F.Adhes" user "F.Adhesive")
    (34 "B.Paste" user)
    (35 "F.Paste" user)
    (36 "B.SilkS" user "B.Silkscreen")
    (37 "F.SilkS" user "F.Silkscreen")
    (38 "B.Mask" user)
    (39 "F.Mask" user)
    (40 "Dwgs.User" user "User.Drawings")
    (41 "Cmts.User" user "User.Comments")
    (42 "Eco1.User" user "User.Eco1")
    (43 "Eco2.User" user "User.Eco2")
    (44 "Edge.Cuts" user)
    (45 "Margin" user)
    (46 "B.CrtYd" user "B.Courtyard")
    (47 "F.CrtYd" user "F.Courtyard")
    (48 "B.Fab" user)
    (49 "F.Fab" user)
  )
	(footprint "antmicro-footprints:C_0603_1608Metric" (layer "F.Cu")
    (at 117.979999 60.5875)
    (descr "Capacitor SMD 0603")
    (tags "capacitor 0603")
    (property "Author" "Antmicro")
    (property "Dielectric" "")
    (property "License" "Apache-2.0")
    (property "MPN" "GRM188R60J226MEA0D")
    (property "Manufacturer" "Murata")
    (property "Sheetfile" "power.kicad_sch")
    (property "Sheetname" "Power")
    (property "Val" "22u")
    (property "Voltage" "")
    (property "ki_description" "SMD Multilayer Ceramic Capacitor, 22 µF, 6.3 V, 0603 [1608 Metric], ± 20%, X5R, GRM Series")
    (property "ki_keywords" "0603, SMT, CAPACITOR, PASSIVE, CERAMIC, MLCC")
    (attr smd)
    (fp_text reference "C47" (at -3.426 0.479) (layer "F.SilkS")
        (effects (font (size 0.7 0.7) (thickness 0.15)) (justify left bottom))
    )
    (fp_text value "C_22u_0603" (at -1.42757 1.770288) (layer "F.Fab")
        (effects (font (size 0.7 0.7) (thickness 0.15)) (justify left bottom))
    )
    (fp_text user "License: Apache-2.0" (at -1.682 5.895) (layer "F.Fab") hide
        (effects (font (size 0.7 0.7) (thickness 0.15)) (justify left bottom))
    )
    (fp_text user "Author: Antmicro" (at -1.682 4.894) (layer "F.Fab") hide
        (effects (font (size 0.7 0.7) (thickness 0.15)) (justify left bottom))
    )
    (fp_text user "${REFERENCE}" (at -1.682 3.895) (layer "F.Fab") hide
        (effects (font (size 0.7 0.7) (thickness 0.15)) (justify left bottom))
    )
    (fp_line (start -0.15 -0.4) (end 0.15 -0.4)
      (stroke (width 0.15) (type solid)) (layer "F.SilkS"))
    (fp_line (start -0.15 0.4) (end 0.15 0.4)
      (stroke (width 0.15) (type solid)) (layer "F.SilkS"))
    (fp_rect (start -1.25 -0.65) (end 1.25 0.65)
      (stroke (width 0.05) (type solid)) (fill none) (layer "F.CrtYd"))
    (fp_rect (start -0.8 -0.4) (end 0.8 0.4)
      (stroke (width 0.15) (type solid)) (fill none) (layer "F.Fab"))
    (pad "1" smd roundrect (at -0.7 0) (size 0.8 1) (layers "F.Cu" "F.Paste" "F.Mask") (roundrect_rratio 0.2)
      (net 1 "GND") (pintype "passive"))
    (pad "2" smd roundrect (at 0.7 0) (size 0.8 1) (layers "F.Cu" "F.Paste" "F.Mask") (roundrect_rratio 0.2)
      (net 100 "Net-(D2-A)") (pintype "passive"))
  )
	(footprint "antmicro-footprints:C_1206_3216Metric" (layer "F.Cu")
    (at 108.750001 64.255 90)
    (descr "Capacitor SMD 1206")
    (tags "capacitor SMD 1206")
    (property "Author" "Antmicro")
    (property "Dielectric" "")
    (property "License" "Apache-2.0")
    (property "MPN" "3216X5R1V226M160AC")
    (property "Manufacturer" "TDK")
    (property "Sheetfile" "power.kicad_sch")
    (property "Sheetname" "Power")
    (property "Val" "22u")
    (property "Voltage" "35V")
    (property "ki_description" "SMD Multilayer Ceramic Capacitors, 22µF, 35V, X5R, 1206 [2316 Metric], 20% ")
    (property "ki_keywords" "1206, SMT, CAPACITOR, PASSIVE, CERAMIC, MLCC")
    (attr smd)
    (fp_text reference "C13" (at -4.325 0.342999 90) (layer "F.SilkS")
        (effects (font (size 0.7 0.7) (thickness 0.15)) (justify left bottom))
    )
    (fp_text value "C_22u_1206_35V" (at 0 2.101 90) (layer "F.Fab")
        (effects (font (size 0.7 0.7) (thickness 0.15)) (justify left bottom))
    )
    (fp_text user "Author: Antmicro" (at -2.625 5.301 90) (layer "F.Fab") hide
        (effects (font (size 0.7 0.7) (thickness 0.15)) (justify left bottom))
    )
    (fp_text user "License: Apache-2.0" (at -2.625 6.501 90) (layer "F.Fab") hide
        (effects (font (size 0.7 0.7) (thickness 0.15)) (justify left bottom))
    )
    (fp_text user "${REFERENCE}" (at -2.625 4.101 90) (layer "F.Fab") hide
        (effects (font (size 0.7 0.7) (thickness 0.15)) (justify left bottom))
    )
    (fp_line (start 0.8 -0.899) (end -0.8 -0.899)
      (stroke (width 0.15) (type solid)) (layer "F.SilkS"))
    (fp_line (start 0.8 0.901) (end -0.8 0.901)
      (stroke (width 0.15) (type solid)) (layer "F.SilkS"))
    (fp_rect (start -2.325 -1.15) (end 2.325 1.15)
      (stroke (width 0.05) (type default)) (fill none) (layer "F.CrtYd"))
    (fp_rect (start -1.6 -0.799) (end 1.6 0.801)
      (stroke (width 0.15) (type solid)) (fill none) (layer "F.Fab"))
    (pad "1" smd roundrect (at -1.5 0.001 90) (size 1.15 1.8) (layers "F.Cu" "F.Paste" "F.Mask") (roundrect_rratio 0.25)
      (net 1 "GND") (pintype "passive"))
    (pad "2" smd roundrect (at 1.5 0.001 90) (size 1.15 1.8) (layers "F.Cu" "F.Paste" "F.Mask") (roundrect_rratio 0.25)
      (net 90 "Net-(U2-VIN)") (pintype "passive"))
  )
	(footprint "antmicro-footprints:Vishay_PowerPAK_1212-8_Single" (layer "F.Cu")
    (at 110.625 90.8 180)
    (descr "PowerPAK 1212-8 Single")
    (tags "Vishay PowerPAK 1212-8 Single")
    (property "Author" "Antmicro")
    (property "License" "Apache-2.0")
    (property "MPN" "SI7613DN-T1-GE3")
    (property "Manufacturer" "Vishay")
    (property "Sheetfile" "power.kicad_sch")
    (property "Sheetname" "Power")
    (property "ki_description" "Power MOSFET, P Channel, 20 V, 35 A, 0.0072 ohm, PowerPAK 1212, Surface Mount")
    (property "ki_keywords" "SMT, TRANSISTOR, SEMICONDUCTOR, MOSFET, PMOS")
    (attr smd)
    (fp_text reference "Q5" (at 0.643 -2.799 180) (layer "F.SilkS")
        (effects (font (size 0.7 0.7) (thickness 0.15)) (justify left bottom))
    )
    (fp_text value "SI7613DN-T1-GE3" (at 0 2.7 180) (layer "F.Fab")
        (effects (font (size 0.7 0.7) (thickness 0.15)) (justify left bottom))
    )
    (fp_text user "License: Apache-2.0" (at -8 7.1 180) (layer "F.Fab") hide
        (effects (font (size 0.7 0.7) (thickness 0.15)) (justify left bottom))
    )
    (fp_text user "${REFERENCE}" (at -8 4.7 180) (layer "F.Fab") hide
        (effects (font (size 0.7 0.7) (thickness 0.15)) (justify left bottom))
    )
    (fp_text user "Author: Antmicro" (at -8 5.9 180) (layer "F.Fab") hide
        (effects (font (size 0.7 0.7) (thickness 0.15)) (justify left bottom))
    )
    (fp_line (start -1.651 -1.651) (end -1.651 -1.317)
      (stroke (width 0.15) (type solid)) (layer "F.SilkS"))
    (fp_line (start -1.651 -1.651) (end 1.648 -1.651)
      (stroke (width 0.15) (type solid)) (layer "F.SilkS"))
    (fp_line (start -1.635 1.3) (end -1.635 1.634)
      (stroke (width 0.15) (type solid)) (layer "F.SilkS"))
    (fp_line (start -1.635 1.634) (end 1.634 1.634)
      (stroke (width 0.15) (type solid)) (layer "F.SilkS"))
    (fp_line (start 1.634 1.3) (end 1.634 1.634)
      (stroke (width 0.15) (type solid)) (layer "F.SilkS"))
    (fp_line (start 1.648 -1.651) (end 1.648 -1.317)
      (stroke (width 0.15) (type solid)) (layer "F.SilkS"))
    (fp_circle (center -1.9 -1.4) (end -1.85 -1.4)
      (stroke (width 0.15) (type solid)) (fill solid) (layer "F.SilkS"))
    (fp_rect (start -2 -1.8) (end 2 1.798)
      (stroke (width 0.05) (type solid)) (fill none) (layer "F.CrtYd"))
    (fp_line (start -1.6425 -1.4175) (end -1.4175 -1.6425)
      (stroke (width 0.15) (type solid)) (layer "F.Fab"))
    (fp_rect (start -1.651 -1.651) (end 1.648 1.648)
      (stroke (width 0.15) (type solid)) (fill none) (layer "F.Fab"))
    (pad "1" smd rect (at -1.436 -0.99 180) (size 0.99 0.405) (layers "F.Cu" "F.Paste" "F.Mask")
      (net 143 "Net-(Q3-S)") (pinfunction "S") (pintype "passive"))
    (pad "2" smd rect (at -1.436 -0.332 180) (size 0.99 0.405) (layers "F.Cu" "F.Paste" "F.Mask")
      (net 143 "Net-(Q3-S)") (pinfunction "S") (pintype "passive"))
    (pad "3" smd rect (at -1.436 0.33 180) (size 0.99 0.405) (layers "F.Cu" "F.Paste" "F.Mask")
      (net 143 "Net-(Q3-S)") (pinfunction "S") (pintype "passive"))
    (pad "4" smd rect (at -1.436 0.988 180) (size 0.99 0.405) (layers "F.Cu" "F.Paste" "F.Mask")
      (net 142 "Net-(Q3-BIAS)") (pinfunction "G") (pintype "passive"))
    (pad "5" smd custom (at 0.557 0 180) (size 1.725 2.235) (layers "F.Cu" "F.Paste" "F.Mask")
      (net 61 "12V0_MOLEX") (pinfunction "D") (pintype "passive") (zone_connect 2)
      (options (clearance outline) (anchor rect))
      (primitives
        (gr_poly
          (pts
            (xy 0.8625 0.1275)
            (xy 0.8625 -0.1275)
            (xy 1.3725 -0.1275)
            (xy 1.3725 -0.5325)
            (xy 0.8625 -0.5325)
            (xy 0.8625 -0.7875)
            (xy 1.3725 -0.7875)
            (xy 1.3725 -1.195)
            (xy 0.6125 -1.195)
            (xy 0.6125 1.195)
            (xy 1.3725 1.195)
            (xy 1.3725 0.7875)
            (xy 0.8625 0.7875)
            (xy 0.8625 0.5325)
            (xy 1.3725 0.5325)
            (xy 1.3725 0.1275)
          )
          (width 0) (fill yes))
      ))
  )
	(footprint "antmicro-footprints:R_1206_3216Metric" (layer "F.Cu")
    (at 116.16 86.35 -90)
    (property "Author" "Antmicro")
    (property "License" "Apache-2.0")
    (property "MPN" "WSLP1206R0200FEA")
    (property "Manufacturer" "Vishay")
    (property "Sheetfile" "power.kicad_sch")
    (property "Sheetname" "Power")
    (property "Tolerance" "1%")
    (property "Val" "0R02")
    (property "ki_description" "Wirewound resistor, 0.02 ohm, 1W, ±1%")
    (property "ki_keywords" "1206, SMT, RESISTOR, PASSIVE")
    (attr smd)
    (fp_text reference "R45" (at -2.022 -2.204 -90) (layer "F.SilkS")
        (effects (font (size 0.7 0.7) (thickness 0.15)) (justify left bottom))
    )
    (fp_text value "R_0R02_1206" (at -2.422356 2.103591 -90) (layer "F.Fab")
        (effects (font (size 0.7 0.7) (thickness 0.15)) (justify left bottom))
    )
    (fp_text user "${REFERENCE}" (at -2.401 3.5 -90) (layer "F.Fab") hide
        (effects (font (size 0.7 0.7) (thickness 0.15)) (justify left bottom))
    )
    (fp_text user "Author: Antmicro" (at -2.401 4.899 -90) (layer "F.Fab") hide
        (effects (font (size 0.7 0.7) (thickness 0.15)) (justify left bottom))
    )
    (fp_text user "License: Apache-2.0" (at -2.401 6.3 -90) (layer "F.Fab") hide
        (effects (font (size 0.7 0.7) (thickness 0.15)) (justify left bottom))
    )
    (fp_line (start 0.8 -0.899) (end -0.8 -0.899)
      (stroke (width 0.15) (type solid)) (layer "F.SilkS"))
    (fp_line (start 0.8 0.901) (end -0.8 0.901)
      (stroke (width 0.15) (type solid)) (layer "F.SilkS"))
    (fp_rect (start -2.325 -1.15) (end 2.325 1.15)
      (stroke (width 0.05) (type default)) (fill none) (layer "F.CrtYd"))
    (fp_line (start -1.601 -0.802) (end -1.601 0.8)
      (stroke (width 0.15) (type solid)) (layer "F.Fab"))
    (fp_line (start -1.601 -0.802) (end 1.6 -0.802)
      (stroke (width 0.15) (type solid)) (layer "F.Fab"))
    (fp_line (start -1.601 0.8) (end 1.6 0.8)
      (stroke (width 0.15) (type solid)) (layer "F.Fab"))
    (fp_line (start 1.6 -0.802) (end 1.6 0.8)
      (stroke (width 0.15) (type solid)) (layer "F.Fab"))
    (pad "1" smd roundrect (at -1.5 0.001 270) (size 1.15 1.8) (layers "F.Cu" "F.Paste" "F.Mask") (roundrect_rratio 0.25)
      (net 75 "Net-(C32-Pad2)") (pintype "passive"))
    (pad "2" smd roundrect (at 1.5 0.001 270) (size 1.15 1.8) (layers "F.Cu" "F.Paste" "F.Mask") (roundrect_rratio 0.25)
      (net 60 "12V0_DCDC") (pintype "passive"))
  )
	(footprint "antmicro-footprints:C_0603_1608Metric" (layer "F.Cu")
    (at 117.98 57.56)
    (descr "Capacitor SMD 0603")
    (tags "capacitor 0603")
    (property "Author" "Antmicro")
    (property "Dielectric" "")
    (property "License" "Apache-2.0")
    (property "MPN" "GRM188R60J226MEA0D")
    (property "Manufacturer" "Murata")
    (property "Sheetfile" "power.kicad_sch")
    (property "Sheetname" "Power")
    (property "Val" "22u")
    (property "Voltage" "")
    (property "ki_description" "SMD Multilayer Ceramic Capacitor, 22 µF, 6.3 V, 0603 [1608 Metric], ± 20%, X5R, GRM Series")
    (property "ki_keywords" "0603, SMT, CAPACITOR, PASSIVE, CERAMIC, MLCC")
    (attr smd)
    (fp_text reference "C41" (at -3.426 0.479) (layer "F.SilkS")
        (effects (font (size 0.7 0.7) (thickness 0.15)) (justify left bottom))
    )
    (fp_text value "C_22u_0603" (at -1.42757 1.770288) (layer "F.Fab")
        (effects (font (size 0.7 0.7) (thickness 0.15)) (justify left bottom))
    )
    (fp_text user "${REFERENCE}" (at -1.682 3.895) (layer "F.Fab") hide
        (effects (font (size 0.7 0.7) (thickness 0.15)) (justify left bottom))
    )
    (fp_text user "License: Apache-2.0" (at -1.682 5.895) (layer "F.Fab") hide
        (effects (font (size 0.7 0.7) (thickness 0.15)) (justify left bottom))
    )
    (fp_text user "Author: Antmicro" (at -1.682 4.894) (layer "F.Fab") hide
        (effects (font (size 0.7 0.7) (thickness 0.15)) (justify left bottom))
    )
    (fp_line (start -0.15 -0.4) (end 0.15 -0.4)
      (stroke (width 0.15) (type solid)) (layer "F.SilkS"))
    (fp_line (start -0.15 0.4) (end 0.15 0.4)
      (stroke (width 0.15) (type solid)) (layer "F.SilkS"))
    (fp_rect (start -1.25 -0.65) (end 1.25 0.65)
      (stroke (width 0.05) (type solid)) (fill none) (layer "F.CrtYd"))
    (fp_rect (start -0.8 -0.4) (end 0.8 0.4)
      (stroke (width 0.15) (type solid)) (fill none) (layer "F.Fab"))
    (pad "1" smd roundrect (at -0.7 0) (size 0.8 1) (layers "F.Cu" "F.Paste" "F.Mask") (roundrect_rratio 0.2)
      (net 1 "GND") (pintype "passive"))
    (pad "2" smd roundrect (at 0.7 0) (size 0.8 1) (layers "F.Cu" "F.Paste" "F.Mask") (roundrect_rratio 0.2)
      (net 100 "Net-(D2-A)") (pintype "passive"))
  )
	(footprint "antmicro-footprints:TP_SMD_1mm" (layer "F.Cu")
    (at 111.7 88.3)
    (property "Author" "Antmicro")
    (property "License" "Apache-2.0")
    (property "MPN" "")
    (property "Manufacturer" "")
    (property "Sheetfile" "power.kicad_sch")
    (property "Sheetname" "Power")
    (property "exclude_from_bom" "")
    (property "ki_description" "Test point 1mm SMD")
    (property "ki_keywords" "TESTPOINT")
    (attr exclude_from_pos_files exclude_from_bom)
    (fp_text reference "TP3" (at -1.21 -0.797) (layer "F.SilkS")
        (effects (font (size 0.7 0.7) (thickness 0.15)) (justify left bottom))
    )
    (fp_text value "TP_1mm_SMD" (at 0 1.4) (layer "F.Fab")
        (effects (font (size 0.7 0.7) (thickness 0.15)) (justify left bottom))
    )
    (fp_text user "${REFERENCE}" (at -0.5 2.8) (layer "F.Fab") hide
        (effects (font (size 0.7 0.7) (thickness 0.15)) (justify left bottom))
    )
    (fp_text user "License: Apache-2.0" (at -0.5 5.2) (layer "F.Fab") hide
        (effects (font (size 0.7 0.7) (thickness 0.15)) (justify left bottom))
    )
    (fp_text user "Author: Antmicro" (at -0.5 4) (layer "F.Fab") hide
        (effects (font (size 0.7 0.7) (thickness 0.15)) (justify left bottom))
    )
    (fp_circle (center 0 0) (end 0.6 0)
      (stroke (width 0.05) (type default)) (fill none) (layer "F.CrtYd"))
    (pad "1" smd circle (at 0 0) (size 1 1) (layers "F.Cu" "F.Mask")
      (net 157 "Net-(U1-~{PGOOD})") (pinfunction "1") (pintype "passive"))
  )
	(footprint "antmicro-footprints:MP_Pad6mm_Drill3mm" (layer "F.Cu")
    (at 104 54)
    (property "Author" "Antmicro")
    (property "License" "Apache-2.0")
    (property "Sheetfile" "connectors.kicad_sch")
    (property "Sheetname" "Connectors")
    (property "exclude_from_bom" "")
    (property "ki_description" "Mechanical part")
    (property "ki_keywords" "MECHANICAL")
    (attr exclude_from_pos_files exclude_from_bom)
    (fp_text reference "MP1" (at 0 -3.2) (layer "F.SilkS") hide
        (effects (font (size 0.7 0.7) (thickness 0.15)) (justify left bottom))
    )
    (fp_text value "MP_Pad6mm_Drill3mm" (at 0 3.9) (layer "F.Fab")
        (effects (font (size 0.7 0.7) (thickness 0.15)) (justify left bottom))
    )
    (fp_text user "License: Apache-2.0" (at -0.178 8.425) (layer "F.Fab") hide
        (effects (font (size 0.7 0.7) (thickness 0.15)) (justify left bottom))
    )
    (fp_text user "${REFERENCE}" (at -0.178 6.025) (layer "F.Fab") hide
        (effects (font (size 0.7 0.7) (thickness 0.15)) (justify left bottom))
    )
    (fp_text user "Author: Antmicro" (at -0.178 7.225) (layer "F.Fab") hide
        (effects (font (size 0.7 0.7) (thickness 0.15)) (justify left bottom))
    )
    (fp_circle (center 0 0) (end 3.25 0)
      (stroke (width 0.05) (type default)) (fill none) (layer "F.CrtYd"))
    (pad "1" thru_hole circle (at 0 0) (size 6 6) (drill 3) (layers "*.Cu" "*.Mask")
      (net 1 "GND") (pintype "passive"))
  )
	(footprint "antmicro-footprints:SOIC-8_5.3x5.3x2mm_P1.27mm" (layer "F.Cu")
    (at 137.147856 62.3)
    (descr "8-Pin SOIC 208-mil")
    (property "Author" "Antmicro")
    (property "License" "Apache-2.0")
    (property "MPN" "MX25L8006EM2I-12G")
    (property "Manufacturer" "Macronix")
    (property "Sheetfile" "tb.kicad_sch")
    (property "Sheetname" "TB Controller")
    (property "dnp" "")
    (property "ki_description" "FLASH - NOR Memory IC 8Mbit SPI 86 MHz 8-SOP")
    (property "ki_keywords" "SMT, MEMORY, IC, FLASH, SPI")
    (attr smd)
    (fp_text reference "U7" (at 0.520144 -3.245) (layer "F.SilkS")
        (effects (font (size 0.7 0.7) (thickness 0.15)) (justify left bottom))
    )
    (fp_text value "MX25L8006EM2I-12G" (at 0 3.8) (layer "F.Fab")
        (effects (font (size 0.7 0.7) (thickness 0.15)) (justify left bottom))
    )
    (fp_text user "License: Apache-2.0" (at -4.675 6.938) (layer "F.Fab") hide
        (effects (font (size 0.7 0.7) (thickness 0.15)) (justify left bottom))
    )
    (fp_text user "Author: Antmicro" (at -4.675 5.938) (layer "F.Fab") hide
        (effects (font (size 0.7 0.7) (thickness 0.15)) (justify left bottom))
    )
    (fp_text user "${REFERENCE}" (at -4.675 4.938) (layer "F.Fab") hide
        (effects (font (size 0.7 0.7) (thickness 0.15)) (justify left bottom))
    )
    (fp_line (start -2.8 -2.641) (end -4.4 -2.641)
      (stroke (width 0.15) (type solid)) (layer "F.SilkS"))
    (fp_circle (center -4.85 -1.905) (end -4.8 -1.855)
      (stroke (width 0.15) (type solid)) (fill solid) (layer "F.SilkS"))
    (fp_rect (start 4.675 -3) (end -4.675 3)
      (stroke (width 0.05) (type solid)) (fill none) (layer "F.CrtYd"))
    (fp_line (start -2.641 -2.641) (end 2.64 -2.641)
      (stroke (width 0.15) (type solid)) (layer "F.Fab"))
    (fp_line (start -2.641 -1.371) (end -1.371 -2.641)
      (stroke (width 0.15) (type solid)) (layer "F.Fab"))
    (fp_line (start -2.641 2.64) (end -2.641 -2.641)
      (stroke (width 0.15) (type solid)) (layer "F.Fab"))
    (fp_line (start 2.64 -2.641) (end 2.64 2.64)
      (stroke (width 0.15) (type solid)) (layer "F.Fab"))
    (fp_line (start 2.64 2.64) (end -2.641 2.64)
      (stroke (width 0.15) (type solid)) (layer "F.Fab"))
    (pad "1" smd roundrect (at -3.601 -1.905 90) (size 0.65 1.65) (layers "F.Cu" "F.Paste" "F.Mask") (roundrect_rratio 0.25)
      (net 65 "SPI_CS") (pinfunction "~{CS}") (pintype "input"))
    (pad "2" smd roundrect (at -3.601 -0.635 90) (size 0.65 1.65) (layers "F.Cu" "F.Paste" "F.Mask") (roundrect_rratio 0.25)
      (net 63 "SPI_MISO") (pinfunction "SO/IO1") (pintype "input"))
    (pad "3" smd roundrect (at -3.601 0.633 90) (size 0.65 1.65) (layers "F.Cu" "F.Paste" "F.Mask") (roundrect_rratio 0.25)
      (net 64 "/TB Controller/FLASH_WP") (pinfunction "~{WP}") (pintype "input"))
    (pad "4" smd roundrect (at -3.601 1.904 90) (size 0.65 1.65) (layers "F.Cu" "F.Paste" "F.Mask") (roundrect_rratio 0.25)
      (net 1 "GND") (pinfunction "GND") (pintype "power_in"))
    (pad "5" smd roundrect (at 3.6 1.904 90) (size 0.65 1.65) (layers "F.Cu" "F.Paste" "F.Mask") (roundrect_rratio 0.25)
      (net 69 "SPI_MOSI") (pinfunction "SI/IO0") (pintype "input"))
    (pad "6" smd roundrect (at 3.6 0.633 90) (size 0.65 1.65) (layers "F.Cu" "F.Paste" "F.Mask") (roundrect_rratio 0.25)
      (net 68 "SPI_SCLK") (pinfunction "SCLK") (pintype "input"))
    (pad "7" smd roundrect (at 3.6 -0.635 90) (size 0.65 1.65) (layers "F.Cu" "F.Paste" "F.Mask") (roundrect_rratio 0.25)
      (net 89 "/TB Controller/FLASH_HOLD") (pinfunction "~{HOLD}") (pintype "input"))
    (pad "8" smd roundrect (at 3.6 -1.905 90) (size 0.65 1.65) (layers "F.Cu" "F.Paste" "F.Mask") (roundrect_rratio 0.25)
      (net 2 "3V3_SYS") (pinfunction "VCC") (pintype "power_in"))
  )
)
